# S9S_MB_2U (Grand Teton) — schematic netlist excerpt (pin names and nets, part order shuffled) for the footprints in the layout excerpt that follows; sources: Cadence DE-HDL packaged netlist, KiCad conversion of 03242023_DA0F0TMBIJ0_F0T_Motherboard_J_brd_V01_OCP.brd

R3727  Q_RES  2.2K 5% CHIP  pkg 0402LF  page 233 : A = P3V3_AUX ; B = SMB_LM75_1_3V3AUX_SCL
C1766  Q_CAP  0.1UF 25V 10% X7R  pkg 0402  page 234 : A = P3V3_AUX ; B = GND

(kicad_pcb
	(version 20260206)
	(generator "pcbnew")
	(generator_version "10.0")
	(general
		(thickness 1.6)
		(legacy_teardrops no)
	)
	(paper "A4")
	(title_block
		(title "03242023_DA0F0TMBIJ0_F0T_Motherboard_J_brd_V01_OCP.brd")
		(comment 1 "Grand Teton / footprints 2003-2004 of 6105")
	)
	(layers
		(0 "F.Cu" signal "TOP")
		(4 "In1.Cu" signal "GND")
		(6 "In2.Cu" signal "IN1")
		(8 "In3.Cu" signal "GND1")
		(10 "In4.Cu" signal "IN2")
		(12 "In5.Cu" signal "GND2")
		(14 "In6.Cu" signal "IN3")
		(16 "In7.Cu" signal "GND3")
		(18 "In8.Cu" signal "VCC")
		(20 "In9.Cu" signal "VCC1")
		(22 "In10.Cu" signal "GND4")
		(24 "In11.Cu" signal "IN4")
		(26 "In12.Cu" signal "GND5")
		(28 "In13.Cu" signal "IN5")
		(30 "In14.Cu" signal "GND6")
		(32 "In15.Cu" signal "IN6")
		(34 "In16.Cu" signal "GND7")
		(2 "B.Cu" signal "BOTTOM")
		(9 "F.Adhes" user "F.Adhesive")
		(11 "B.Adhes" user "B.Adhesive")
		(13 "F.Paste" user "Package Geometry/Pastemask Top")
		(15 "B.Paste" user "Package Geometry/Pastemask Bottom")
		(5 "F.SilkS" user "Ref Des/Silkscreen Top")
		(7 "B.SilkS" user "Ref Des/Silkscreen Bottom")
		(1 "F.Mask" user "Board Geometry/Soldermask Top")
		(3 "B.Mask" user "Board Geometry/Soldermask Bottom")
		(17 "Dwgs.User" user "User.Drawings")
		(19 "Cmts.User" user "User.Comments")
		(21 "Eco1.User" user "User.Eco1")
		(23 "Eco2.User" user "User.Eco2")
		(25 "Edge.Cuts" user "Board Geometry/Outline")
		(27 "Margin" user)
		(31 "F.CrtYd" user "Package Geometry/Place Bound Top")
		(29 "B.CrtYd" user "Package Geometry/Place Bound Bottom")
		(35 "F.Fab" user "Ref Des/Assembly Top")
		(33 "B.Fab" user "Ref Des/Assembly Bottom")
	)
	(footprint ""
		(layer "F.Cu")
		(at 51.593496 -108.14177)
		(property "Reference" "R3727"
			(at 0 0 0)
			(layer "F.SilkS")
			(hide yes)
			(effects
				(font
					(size 1.27 1.27)
				)
			)
		)
		(property "Value" ""
			(at 0 0 0)
			(layer "F.Fab")
			(effects
				(font
					(size 1.27 1.27)
				)
			)
		)
		(duplicate_pad_numbers_are_jumpers no)
		(fp_line
			(start -0.7874 -0.4064)
			(end 0.7874 -0.4064)
			(stroke
				(width 0.1524)
				(type default)
			)
			(layer "F.SilkS")
		)
		(fp_line
			(start -0.7874 0.4064)
			(end -0.7874 -0.4064)
			(stroke
				(width 0.1524)
				(type default)
			)
			(layer "F.SilkS")
		)
		(fp_line
			(start 0.7874 -0.4064)
			(end 0.7874 0.4064)
			(stroke
				(width 0.1524)
				(type default)
			)
			(layer "F.SilkS")
		)
		(fp_line
			(start 0.7874 0.4064)
			(end -0.7874 0.4064)
			(stroke
				(width 0.1524)
				(type default)
			)
			(layer "F.SilkS")
		)
		(fp_line
			(start -0.67945 -0.305054)
			(end -0.12065 -0.305054)
			(stroke
				(width 0.1)
				(type default)
			)
			(layer "F.Fab")
		)
		(fp_line
			(start -0.67945 0.3048)
			(end -0.67945 -0.305054)
			(stroke
				(width 0.1)
				(type default)
			)
			(layer "F.Fab")
		)
		(fp_line
			(start -0.12065 -0.305054)
			(end -0.12065 -0.2794)
			(stroke
				(width 0.1)
				(type default)
			)
			(layer "F.Fab")
		)
		(fp_line
			(start -0.12065 -0.2794)
			(end 0.12065 -0.2794)
			(stroke
				(width 0.1)
				(type default)
			)
			(layer "F.Fab")
		)
		(fp_line
			(start -0.12065 0.2794)
			(end -0.12065 0.3048)
			(stroke
				(width 0.1)
				(type default)
			)
			(layer "F.Fab")
		)
		(fp_line
			(start -0.12065 0.3048)
			(end -0.67945 0.3048)
			(stroke
				(width 0.1)
				(type default)
			)
			(layer "F.Fab")
		)
		(fp_line
			(start 0.120396 0.2794)
			(end -0.12065 0.2794)
			(stroke
				(width 0.1)
				(type default)
			)
			(layer "F.Fab")
		)
		(fp_line
			(start 0.120396 0.3048)
			(end 0.120396 0.2794)
			(stroke
				(width 0.1)
				(type default)
			)
			(layer "F.Fab")
		)
		(fp_line
			(start 0.12065 -0.3048)
			(end 0.67945 -0.3048)
			(stroke
				(width 0.1)
				(type default)
			)
			(layer "F.Fab")
		)
		(fp_line
			(start 0.12065 -0.2794)
			(end 0.12065 -0.3048)
			(stroke
				(width 0.1)
				(type default)
			)
			(layer "F.Fab")
		)
		(fp_line
			(start 0.67945 -0.3048)
			(end 0.67945 0.3048)
			(stroke
				(width 0.1)
				(type default)
			)
			(layer "F.Fab")
		)
		(fp_line
			(start 0.67945 0.3048)
			(end 0.120396 0.3048)
			(stroke
				(width 0.1)
				(type default)
			)
			(layer "F.Fab")
		)
		(pad "1" smd circle
			(at -0.40005 0)
			(size 0 0)
			(layers "F.Cu" "F.Mask" "F.Paste")
			(net "P3V3_AUX")
		)
		(pad "2" smd circle
			(at 0.40005 0)
			(size 0 0)
			(layers "F.Cu" "F.Mask" "F.Paste")
			(net "SMB_LM75_1_3V3AUX_SCL")
		)
	)
	(footprint ""
		(layer "F.Cu")
		(at 49.496472 -436.803038)
		(property "Reference" "C1766"
			(at 0 0 0)
			(layer "F.SilkS")
			(hide yes)
			(effects
				(font
					(size 1.27 1.27)
				)
			)
		)
		(property "Value" ""
			(at 0 0 0)
			(layer "F.Fab")
			(effects
				(font
					(size 1.27 1.27)
				)
			)
		)
		(duplicate_pad_numbers_are_jumpers no)
		(fp_line
			(start -0.7874 -0.4064)
			(end 0.7874 -0.4064)
			(stroke
				(width 0.1524)
				(type default)
			)
			(layer "F.SilkS")
		)
		(fp_line
			(start -0.7874 0.4064)
			(end -0.7874 -0.4064)
			(stroke
				(width 0.1524)
				(type default)
			)
			(layer "F.SilkS")
		)
		(fp_line
			(start 0.7874 -0.4064)
			(end 0.7874 0.4064)
			(stroke
				(width 0.1524)
				(type default)
			)
			(layer "F.SilkS")
		)
		(fp_line
			(start 0.7874 0.4064)
			(end -0.7874 0.4064)
			(stroke
				(width 0.1524)
				(type default)
			)
			(layer "F.SilkS")
		)
		(fp_line
			(start -0.67945 -0.305054)
			(end -0.12065 -0.305054)
			(stroke
				(width 0.1)
				(type default)
			)
			(layer "F.Fab")
		)
		(fp_line
			(start -0.67945 0.3048)
			(end -0.67945 -0.305054)
			(stroke
				(width 0.1)
				(type default)
			)
			(layer "F.Fab")
		)
		(fp_line
			(start -0.12065 -0.305054)
			(end -0.12065 -0.2794)
			(stroke
				(width 0.1)
				(type default)
			)
			(layer "F.Fab")
		)
		(fp_line
			(start -0.12065 -0.2794)
			(end 0.12065 -0.2794)
			(stroke
				(width 0.1)
				(type default)
			)
			(layer "F.Fab")
		)
		(fp_line
			(start -0.12065 0.2794)
			(end -0.12065 0.3048)
			(stroke
				(width 0.1)
				(type default)
			)
			(layer "F.Fab")
		)
		(fp_line
			(start -0.12065 0.3048)
			(end -0.67945 0.3048)
			(stroke
				(width 0.1)
				(type default)
			)
			(layer "F.Fab")
		)
		(fp_line
			(start 0.120396 0.2794)
			(end -0.12065 0.2794)
			(stroke
				(width 0.1)
				(type default)
			)
			(layer "F.Fab")
		)
		(fp_line
			(start 0.120396 0.3048)
			(end 0.120396 0.2794)
			(stroke
				(width 0.1)
				(type default)
			)
			(layer "F.Fab")
		)
		(fp_line
			(start 0.12065 -0.3048)
			(end 0.67945 -0.3048)
			(stroke
				(width 0.1)
				(type default)
			)
			(layer "F.Fab")
		)
		(fp_line
			(start 0.12065 -0.2794)
			(end 0.12065 -0.3048)
			(stroke
				(width 0.1)
				(type default)
			)
			(layer "F.Fab")
		)
		(fp_line
			(start 0.67945 -0.3048)
			(end 0.67945 0.3048)
			(stroke
				(width 0.1)
				(type default)
			)
			(layer "F.Fab")
		)
		(fp_line
			(start 0.67945 0.3048)
			(end 0.120396 0.3048)
			(stroke
				(width 0.1)
				(type default)
			)
			(layer "F.Fab")
		)
		(pad "1" smd circle
			(at -0.40005 0)
			(size 0 0)
			(layers "F.Cu" "F.Mask" "F.Paste")
			(net "P3V3_AUX")
		)
		(pad "2" smd circle
			(at 0.40005 0)
			(size 0 0)
			(layers "F.Cu" "F.Mask" "F.Paste")
			(net "GND")
		)
	)
)
